#ISCELL
  pure_quanta quanta_title_block_c *
  *
#CELL
  pure_quanta pt5161lrs *
  page426_i1
#ISCELL
  standard tap *
  page426_i10
#ISCELL
  standard tap *
  page426_i11
#ISCELL
  standard tap *
  page426_i12
#ISCELL
  standard tap *
  page426_i13
#ISCELL
  standard tap *
  page426_i14
#ISCELL
  standard tap *
  page426_i15
#ISCELL
  standard tap *
  page426_i16
#ISCELL
  standard tap *
  page426_i17
#ISCELL
  standard offpage *
  page426_i18
#ISCELL
  standard offpage *
  page426_i19
#ISCELL
  standard tap *
  page426_i2
#ISCELL
  standard tap *
  page426_i20
#ISCELL
  standard tap *
  page426_i21
#ISCELL
  standard tap *
  page426_i22
#ISCELL
  standard tap *
  page426_i23
#ISCELL
  standard tap *
  page426_i24
#ISCELL
  standard tap *
  page426_i25
#ISCELL
  standard tap *
  page426_i26
#ISCELL
  standard tap *
  page426_i27
#ISCELL
  standard tap *
  page426_i28
#ISCELL
  standard tap *
  page426_i29
#ISCELL
  standard tap *
  page426_i3
#ISCELL
  standard tap *
  page426_i30
#ISCELL
  standard tap *
  page426_i31
#ISCELL
  standard tap *
  page426_i32
#ISCELL
  standard tap *
  page426_i33
#ISCELL
  standard offpage *
  page426_i34
#ISCELL
  standard offpage *
  page426_i35
#ISCELL
  standard tap *
  page426_i36
#ISCELL
  standard tap *
  page426_i37
#CELL
  pure_quanta pt5161lrs *
  page426_i38
#ISCELL
  standard tap *
  page426_i4
#ISCELL
  standard tap *
  page426_i5
#ISCELL
  standard tap *
  page426_i6
#ISCELL
  standard tap *
  page426_i7
#ISCELL
  standard tap *
  page426_i8
#ISCELL
  standard tap *
  page426_i9
